(kicad_pcb
	(version 20260206)
	(generator "pcbnew")
	(generator_version "10.0")
	(general
		(thickness 1.6)
		(legacy_teardrops no)
	)
	(paper "A4")
	(title_block
		(title "01162023_DA0F0TEBIF0_F0T_Expander_BD_F_brd_V02_OCP.brd")
		(comment 1 "Grand Teton / footprints 2989-2996 of 9728")
	)
	(layers
		(0 "F.Cu" signal "TOP")
		(4 "In1.Cu" signal "GND")
		(6 "In2.Cu" signal "VCC")
		(8 "In3.Cu" signal "VCC1")
		(10 "In4.Cu" signal "GND1")
		(12 "In5.Cu" signal "IN1")
		(14 "In6.Cu" signal "GND2")
		(16 "In7.Cu" signal "IN2")
		(18 "In8.Cu" signal "GND3")
		(20 "In9.Cu" signal "IN3")
		(22 "In10.Cu" signal "GND4")
		(24 "In11.Cu" signal "IN4")
		(26 "In12.Cu" signal "GND5")
		(28 "In13.Cu" signal "IN5")
		(30 "In14.Cu" signal "GND6")
		(32 "In15.Cu" signal "IN6")
		(34 "In16.Cu" signal "GND7")
		(2 "B.Cu" signal "BOTTOM")
		(9 "F.Adhes" user "F.Adhesive")
		(11 "B.Adhes" user "B.Adhesive")
		(13 "F.Paste" user "Package Geometry/Pastemask Top")
		(15 "B.Paste" user "Package Geometry/Pastemask Bottom")
		(5 "F.SilkS" user "Ref Des/Silkscreen Top")
		(7 "B.SilkS" user "Ref Des/Silkscreen Bottom")
		(1 "F.Mask" user "Board Geometry/Soldermask Top")
		(3 "B.Mask" user "Board Geometry/Soldermask Bottom")
		(17 "Dwgs.User" user "User.Drawings")
		(19 "Cmts.User" user "User.Comments")
		(21 "Eco1.User" user "User.Eco1")
		(23 "Eco2.User" user "User.Eco2")
		(25 "Edge.Cuts" user "Board Geometry/Outline")
		(27 "Margin" user)
		(31 "F.CrtYd" user "Package Geometry/Place Bound Top")
		(29 "B.CrtYd" user "Package Geometry/Place Bound Bottom")
		(35 "F.Fab" user "Ref Des/Assembly Top")
		(33 "B.Fab" user "Ref Des/Assembly Bottom")
	)
	(footprint ""
		(layer "F.Cu")
		(at 108.204 -200.1012 -90)
		(property "Reference" "R6629"
			(at 0 0 270)
			(layer "F.SilkS")
			(hide yes)
			(effects
				(font
					(size 1.27 1.27)
				)
			)
		)
		(property "Value" ""
			(at 0 0 270)
			(layer "F.Fab")
			(effects
				(font
					(size 1.27 1.27)
				)
			)
		)
		(duplicate_pad_numbers_are_jumpers no)
		(fp_line
			(start -0.7874 0.4064)
			(end -0.7874 -0.4064)
			(stroke
				(width 0.1524)
				(type default)
			)
			(layer "F.SilkS")
		)
		(fp_line
			(start 0.7874 0.4064)
			(end -0.7874 0.4064)
			(stroke
				(width 0.1524)
				(type default)
			)
			(layer "F.SilkS")
		)
		(fp_line
			(start -0.7874 -0.4064)
			(end 0.7874 -0.4064)
			(stroke
				(width 0.1524)
				(type default)
			)
			(layer "F.SilkS")
		)
		(fp_line
			(start 0.7874 -0.4064)
			(end 0.7874 0.4064)
			(stroke
				(width 0.1524)
				(type default)
			)
			(layer "F.SilkS")
		)
		(fp_line
			(start -0.67945 0.3048)
			(end -0.67945 -0.305054)
			(stroke
				(width 0.1)
				(type default)
			)
			(layer "F.Fab")
		)
		(fp_line
			(start -0.12065 0.3048)
			(end -0.67945 0.3048)
			(stroke
				(width 0.1)
				(type default)
			)
			(layer "F.Fab")
		)
		(fp_line
			(start 0.120396 0.3048)
			(end 0.120396 0.2794)
			(stroke
				(width 0.1)
				(type default)
			)
			(layer "F.Fab")
		)
		(fp_line
			(start 0.67945 0.3048)
			(end 0.120396 0.3048)
			(stroke
				(width 0.1)
				(type default)
			)
			(layer "F.Fab")
		)
		(fp_line
			(start -0.12065 0.2794)
			(end -0.12065 0.3048)
			(stroke
				(width 0.1)
				(type default)
			)
			(layer "F.Fab")
		)
		(fp_line
			(start 0.120396 0.2794)
			(end -0.12065 0.2794)
			(stroke
				(width 0.1)
				(type default)
			)
			(layer "F.Fab")
		)
		(fp_line
			(start -0.12065 -0.2794)
			(end 0.12065 -0.2794)
			(stroke
				(width 0.1)
				(type default)
			)
			(layer "F.Fab")
		)
		(fp_line
			(start 0.12065 -0.2794)
			(end 0.12065 -0.3048)
			(stroke
				(width 0.1)
				(type default)
			)
			(layer "F.Fab")
		)
		(fp_line
			(start 0.12065 -0.3048)
			(end 0.67945 -0.3048)
			(stroke
				(width 0.1)
				(type default)
			)
			(layer "F.Fab")
		)
		(fp_line
			(start 0.67945 -0.3048)
			(end 0.67945 0.3048)
			(stroke
				(width 0.1)
				(type default)
			)
			(layer "F.Fab")
		)
		(fp_line
			(start -0.67945 -0.305054)
			(end -0.12065 -0.305054)
			(stroke
				(width 0.1)
				(type default)
			)
			(layer "F.Fab")
		)
		(fp_line
			(start -0.12065 -0.305054)
			(end -0.12065 -0.2794)
			(stroke
				(width 0.1)
				(type default)
			)
			(layer "F.Fab")
		)
		(pad "1" smd circle
			(at -0.40005 0 270)
			(size 0 0)
			(layers "F.Cu" "F.Mask" "F.Paste")
			(net "UART_PEX1_CLI_BUF_R_TX")
		)
		(pad "2" smd circle
			(at 0.40005 0 270)
			(size 0 0)
			(layers "F.Cu" "F.Mask" "F.Paste")
			(net "UART_PEX1_CLI_CP2108_TX")
		)
	)
	(footprint ""
		(layer "F.Cu")
		(at 240.83391 -156.288994 -90)
		(property "Reference" "PR7029"
			(at 0 0 270)
			(layer "F.SilkS")
			(hide yes)
			(effects
				(font
					(size 1.27 1.27)
				)
			)
		)
		(property "Value" ""
			(at 0 0 270)
			(layer "F.Fab")
			(effects
				(font
					(size 1.27 1.27)
				)
			)
		)
		(duplicate_pad_numbers_are_jumpers no)
		(fp_line
			(start -0.7874 0.4064)
			(end -0.7874 -0.4064)
			(stroke
				(width 0.1524)
				(type default)
			)
			(layer "F.SilkS")
		)
		(fp_line
			(start 0.7874 0.4064)
			(end -0.7874 0.4064)
			(stroke
				(width 0.1524)
				(type default)
			)
			(layer "F.SilkS")
		)
		(fp_line
			(start -0.7874 -0.4064)
			(end 0.7874 -0.4064)
			(stroke
				(width 0.1524)
				(type default)
			)
			(layer "F.SilkS")
		)
		(fp_line
			(start 0.7874 -0.4064)
			(end 0.7874 0.4064)
			(stroke
				(width 0.1524)
				(type default)
			)
			(layer "F.SilkS")
		)
		(fp_line
			(start -0.67945 0.3048)
			(end -0.67945 -0.305054)
			(stroke
				(width 0.1)
				(type default)
			)
			(layer "F.Fab")
		)
		(fp_line
			(start -0.12065 0.3048)
			(end -0.67945 0.3048)
			(stroke
				(width 0.1)
				(type default)
			)
			(layer "F.Fab")
		)
		(fp_line
			(start 0.120396 0.3048)
			(end 0.120396 0.2794)
			(stroke
				(width 0.1)
				(type default)
			)
			(layer "F.Fab")
		)
		(fp_line
			(start 0.67945 0.3048)
			(end 0.120396 0.3048)
			(stroke
				(width 0.1)
				(type default)
			)
			(layer "F.Fab")
		)
		(fp_line
			(start -0.12065 0.2794)
			(end -0.12065 0.3048)
			(stroke
				(width 0.1)
				(type default)
			)
			(layer "F.Fab")
		)
		(fp_line
			(start 0.120396 0.2794)
			(end -0.12065 0.2794)
			(stroke
				(width 0.1)
				(type default)
			)
			(layer "F.Fab")
		)
		(fp_line
			(start -0.12065 -0.2794)
			(end 0.12065 -0.2794)
			(stroke
				(width 0.1)
				(type default)
			)
			(layer "F.Fab")
		)
		(fp_line
			(start 0.12065 -0.2794)
			(end 0.12065 -0.3048)
			(stroke
				(width 0.1)
				(type default)
			)
			(layer "F.Fab")
		)
		(fp_line
			(start 0.12065 -0.3048)
			(end 0.67945 -0.3048)
			(stroke
				(width 0.1)
				(type default)
			)
			(layer "F.Fab")
		)
		(fp_line
			(start 0.67945 -0.3048)
			(end 0.67945 0.3048)
			(stroke
				(width 0.1)
				(type default)
			)
			(layer "F.Fab")
		)
		(fp_line
			(start -0.67945 -0.305054)
			(end -0.12065 -0.305054)
			(stroke
				(width 0.1)
				(type default)
			)
			(layer "F.Fab")
		)
		(fp_line
			(start -0.12065 -0.305054)
			(end -0.12065 -0.2794)
			(stroke
				(width 0.1)
				(type default)
			)
			(layer "F.Fab")
		)
		(pad "1" smd circle
			(at -0.40005 0 270)
			(size 0 0)
			(layers "F.Cu" "F.Mask" "F.Paste")
			(net "P12V_NIC4_CO_OV_FB")
		)
		(pad "2" smd circle
			(at 0.40005 0 270)
			(size 0 0)
			(layers "F.Cu" "F.Mask" "F.Paste")
			(net "GND")
		)
	)
	(footprint ""
		(layer "F.Cu")
		(at 452.543672 -49.95291 180)
		(property "Reference" "R676"
			(at 0 0 180)
			(layer "F.SilkS")
			(hide yes)
			(effects
				(font
					(size 1.27 1.27)
				)
			)
		)
		(property "Value" ""
			(at 0 0 180)
			(layer "F.Fab")
			(effects
				(font
					(size 1.27 1.27)
				)
			)
		)
		(duplicate_pad_numbers_are_jumpers no)
		(fp_line
			(start 0.7874 0.4064)
			(end -0.7874 0.4064)
			(stroke
				(width 0.1524)
				(type default)
			)
			(layer "F.SilkS")
		)
		(fp_line
			(start 0.7874 -0.4064)
			(end 0.7874 0.4064)
			(stroke
				(width 0.1524)
				(type default)
			)
			(layer "F.SilkS")
		)
		(fp_line
			(start -0.7874 0.4064)
			(end -0.7874 -0.4064)
			(stroke
				(width 0.1524)
				(type default)
			)
			(layer "F.SilkS")
		)
		(fp_line
			(start -0.7874 -0.4064)
			(end 0.7874 -0.4064)
			(stroke
				(width 0.1524)
				(type default)
			)
			(layer "F.SilkS")
		)
		(fp_line
			(start 0.67945 0.3048)
			(end 0.120396 0.3048)
			(stroke
				(width 0.1)
				(type default)
			)
			(layer "F.Fab")
		)
		(fp_line
			(start 0.67945 -0.3048)
			(end 0.67945 0.3048)
			(stroke
				(width 0.1)
				(type default)
			)
			(layer "F.Fab")
		)
		(fp_line
			(start 0.12065 -0.2794)
			(end 0.12065 -0.3048)
			(stroke
				(width 0.1)
				(type default)
			)
			(layer "F.Fab")
		)
		(fp_line
			(start 0.12065 -0.3048)
			(end 0.67945 -0.3048)
			(stroke
				(width 0.1)
				(type default)
			)
			(layer "F.Fab")
		)
		(fp_line
			(start 0.120396 0.3048)
			(end 0.120396 0.2794)
			(stroke
				(width 0.1)
				(type default)
			)
			(layer "F.Fab")
		)
		(fp_line
			(start 0.120396 0.2794)
			(end -0.12065 0.2794)
			(stroke
				(width 0.1)
				(type default)
			)
			(layer "F.Fab")
		)
		(fp_line
			(start -0.12065 0.3048)
			(end -0.67945 0.3048)
			(stroke
				(width 0.1)
				(type default)
			)
			(layer "F.Fab")
		)
		(fp_line
			(start -0.12065 0.2794)
			(end -0.12065 0.3048)
			(stroke
				(width 0.1)
				(type default)
			)
			(layer "F.Fab")
		)
		(fp_line
			(start -0.12065 -0.2794)
			(end 0.12065 -0.2794)
			(stroke
				(width 0.1)
				(type default)
			)
			(layer "F.Fab")
		)
		(fp_line
			(start -0.12065 -0.305054)
			(end -0.12065 -0.2794)
			(stroke
				(width 0.1)
				(type default)
			)
			(layer "F.Fab")
		)
		(fp_line
			(start -0.67945 0.3048)
			(end -0.67945 -0.305054)
			(stroke
				(width 0.1)
				(type default)
			)
			(layer "F.Fab")
		)
		(fp_line
			(start -0.67945 -0.305054)
			(end -0.12065 -0.305054)
			(stroke
				(width 0.1)
				(type default)
			)
			(layer "F.Fab")
		)
		(pad "1" smd circle
			(at -0.40005 0 180)
			(size 0 0)
			(layers "F.Cu" "F.Mask" "F.Paste")
			(net "SMB_BIC_I2C6_MUX_SSD_8_15_ADC_R_SCL")
		)
		(pad "2" smd circle
			(at 0.40005 0 180)
			(size 0 0)
			(layers "F.Cu" "F.Mask" "F.Paste")
			(net "SMB_SSD15_ADC_SCL")
		)
	)
	(footprint ""
		(layer "F.Cu")
		(at 461.776572 -268.422882)
		(property "Reference" "C4392"
			(at 0 0 0)
			(layer "F.SilkS")
			(hide yes)
			(effects
				(font
					(size 1.27 1.27)
				)
			)
		)
		(property "Value" ""
			(at 0 0 0)
			(layer "F.Fab")
			(effects
				(font
					(size 1.27 1.27)
				)
			)
		)
		(duplicate_pad_numbers_are_jumpers no)
		(fp_line
			(start -0.299974 -0.150114)
			(end 0.299974 -0.150114)
			(stroke
				(width 0.1)
				(type default)
			)
			(layer "F.Fab")
		)
		(fp_line
			(start -0.299974 0.150114)
			(end -0.299974 -0.150114)
			(stroke
				(width 0.1)
				(type default)
			)
			(layer "F.Fab")
		)
		(fp_line
			(start 0.299974 -0.150114)
			(end 0.299974 0.150114)
			(stroke
				(width 0.1)
				(type default)
			)
			(layer "F.Fab")
		)
		(fp_line
			(start 0.299974 0.150114)
			(end -0.299974 0.150114)
			(stroke
				(width 0.1)
				(type default)
			)
			(layer "F.Fab")
		)
		(pad "1" smd rect
			(at -0.2667 0)
			(size 0.3048 0.381)
			(layers "F.Cu" "F.Mask" "F.Paste")
			(net "P1V25_SERDES_VDDPLL_PEX3")
		)
		(pad "2" smd rect
			(at 0.2667 0)
			(size 0.3048 0.381)
			(layers "F.Cu" "F.Mask" "F.Paste")
			(net "GND")
		)
	)
	(footprint ""
		(layer "F.Cu")
		(at 13.206222 -134.434326)
		(property "Reference" "PC352"
			(at 0 0 0)
			(layer "F.SilkS")
			(hide yes)
			(effects
				(font
					(size 1.27 1.27)
				)
			)
		)
		(property "Value" ""
			(at 0 0 0)
			(layer "F.Fab")
			(effects
				(font
					(size 1.27 1.27)
				)
			)
		)
		(duplicate_pad_numbers_are_jumpers no)
		(fp_line
			(start -0.7874 -0.4064)
			(end 0.7874 -0.4064)
			(stroke
				(width 0.1524)
				(type default)
			)
			(layer "F.SilkS")
		)
		(fp_line
			(start -0.7874 0.4064)
			(end -0.7874 -0.4064)
			(stroke
				(width 0.1524)
				(type default)
			)
			(layer "F.SilkS")
		)
		(fp_line
			(start 0.7874 -0.4064)
			(end 0.7874 0.4064)
			(stroke
				(width 0.1524)
				(type default)
			)
			(layer "F.SilkS")
		)
		(fp_line
			(start 0.7874 0.4064)
			(end -0.7874 0.4064)
			(stroke
				(width 0.1524)
				(type default)
			)
			(layer "F.SilkS")
		)
		(fp_line
			(start -0.67945 -0.305054)
			(end -0.12065 -0.305054)
			(stroke
				(width 0.1)
				(type default)
			)
			(layer "F.Fab")
		)
		(fp_line
			(start -0.67945 0.3048)
			(end -0.67945 -0.305054)
			(stroke
				(width 0.1)
				(type default)
			)
			(layer "F.Fab")
		)
		(fp_line
			(start -0.12065 -0.305054)
			(end -0.12065 -0.2794)
			(stroke
				(width 0.1)
				(type default)
			)
			(layer "F.Fab")
		)
		(fp_line
			(start -0.12065 -0.2794)
			(end 0.12065 -0.2794)
			(stroke
				(width 0.1)
				(type default)
			)
			(layer "F.Fab")
		)
		(fp_line
			(start -0.12065 0.2794)
			(end -0.12065 0.3048)
			(stroke
				(width 0.1)
				(type default)
			)
			(layer "F.Fab")
		)
		(fp_line
			(start -0.12065 0.3048)
			(end -0.67945 0.3048)
			(stroke
				(width 0.1)
				(type default)
			)
			(layer "F.Fab")
		)
		(fp_line
			(start 0.120396 0.2794)
			(end -0.12065 0.2794)
			(stroke
				(width 0.1)
				(type default)
			)
			(layer "F.Fab")
		)
		(fp_line
			(start 0.120396 0.3048)
			(end 0.120396 0.2794)
			(stroke
				(width 0.1)
				(type default)
			)
			(layer "F.Fab")
		)
		(fp_line
			(start 0.12065 -0.3048)
			(end 0.67945 -0.3048)
			(stroke
				(width 0.1)
				(type default)
			)
			(layer "F.Fab")
		)
		(fp_line
			(start 0.12065 -0.2794)
			(end 0.12065 -0.3048)
			(stroke
				(width 0.1)
				(type default)
			)
			(layer "F.Fab")
		)
		(fp_line
			(start 0.67945 -0.3048)
			(end 0.67945 0.3048)
			(stroke
				(width 0.1)
				(type default)
			)
			(layer "F.Fab")
		)
		(fp_line
			(start 0.67945 0.3048)
			(end 0.120396 0.3048)
			(stroke
				(width 0.1)
				(type default)
			)
			(layer "F.Fab")
		)
		(pad "1" smd circle
			(at -0.40005 0)
			(size 0 0)
			(layers "F.Cu" "F.Mask" "F.Paste")
			(net "P12V_AUX")
		)
		(pad "2" smd circle
			(at 0.40005 0)
			(size 0 0)
			(layers "F.Cu" "F.Mask" "F.Paste")
			(net "GND")
		)
	)
	(footprint ""
		(layer "F.Cu")
		(at 102.02926 -277.639272 180)
		(property "Reference" "PC61"
			(at 0 0 180)
			(layer "F.SilkS")
			(hide yes)
			(effects
				(font
					(size 1.27 1.27)
				)
			)
		)
		(property "Value" ""
			(at 0 0 180)
			(layer "F.Fab")
			(effects
				(font
					(size 1.27 1.27)
				)
			)
		)
		(duplicate_pad_numbers_are_jumpers no)
		(fp_line
			(start 1.524 0.762)
			(end -1.524 0.762)
			(stroke
				(width 0.1524)
				(type default)
			)
			(layer "F.SilkS")
		)
		(fp_line
			(start 1.524 -0.762)
			(end 1.524 0.762)
			(stroke
				(width 0.1524)
				(type default)
			)
			(layer "F.SilkS")
		)
		(fp_line
			(start -1.524 0.762)
			(end -1.524 -0.762)
			(stroke
				(width 0.1524)
				(type default)
			)
			(layer "F.SilkS")
		)
		(fp_line
			(start -1.524 -0.762)
			(end 1.524 -0.762)
			(stroke
				(width 0.1524)
				(type default)
			)
			(layer "F.SilkS")
		)
		(fp_line
			(start 1.1049 0.724916)
			(end 1.1049 -0.724916)
			(stroke
				(width 0.1)
				(type default)
			)
			(layer "F.Fab")
		)
		(fp_line
			(start 1.1049 -0.724916)
			(end -1.1049 -0.724916)
			(stroke
				(width 0.1)
				(type default)
			)
			(layer "F.Fab")
		)
		(fp_line
			(start -1.1049 0.724916)
			(end 1.1049 0.724916)
			(stroke
				(width 0.1)
				(type default)
			)
			(layer "F.Fab")
		)
		(fp_line
			(start -1.1049 -0.724916)
			(end -1.1049 0.724916)
			(stroke
				(width 0.1)
				(type default)
			)
			(layer "F.Fab")
		)
		(pad "1" smd rect
			(at -0.889 0)
			(size 1.016 1.27)
			(layers "F.Cu" "F.Mask" "F.Paste")
			(net "SW_P12V_P0V8_PEX0_FLT")
		)
		(pad "2" smd rect
			(at 0.889 0)
			(size 1.016 1.27)
			(layers "F.Cu" "F.Mask" "F.Paste")
			(net "GND")
		)
	)
	(footprint ""
		(layer "F.Cu")
		(at 418.092382 -29.139642 180)
		(property "Reference" "C720"
			(at 0 0 180)
			(layer "F.SilkS")
			(hide yes)
			(effects
				(font
					(size 1.27 1.27)
				)
			)
		)
		(property "Value" ""
			(at 0 0 180)
			(layer "F.Fab")
			(effects
				(font
					(size 1.27 1.27)
				)
			)
		)
		(duplicate_pad_numbers_are_jumpers no)
		(fp_line
			(start 0.299974 0.150114)
			(end -0.299974 0.150114)
			(stroke
				(width 0.1)
				(type default)
			)
			(layer "F.Fab")
		)
		(fp_line
			(start 0.299974 -0.150114)
			(end 0.299974 0.150114)
			(stroke
				(width 0.1)
				(type default)
			)
			(layer "F.Fab")
		)
		(fp_line
			(start -0.299974 0.150114)
			(end -0.299974 -0.150114)
			(stroke
				(width 0.1)
				(type default)
			)
			(layer "F.Fab")
		)
		(fp_line
			(start -0.299974 -0.150114)
			(end 0.299974 -0.150114)
			(stroke
				(width 0.1)
				(type default)
			)
			(layer "F.Fab")
		)
		(pad "1" smd rect
			(at -0.2667 0 180)
			(size 0.3048 0.381)
			(layers "F.Cu" "F.Mask" "F.Paste")
			(net "P5E_PEX3_STN2_TX_DP<36>")
		)
		(pad "2" smd rect
			(at 0.2667 0 180)
			(size 0.3048 0.381)
			(layers "F.Cu" "F.Mask" "F.Paste")
			(net "P5E_PEX3_STN2_TX_C_DP<36>")
		)
	)
	(footprint ""
		(layer "F.Cu")
		(at 194.684142 -29.222954 -90)
		(property "Reference" "PC929"
			(at 0 0 270)
			(layer "F.SilkS")
			(hide yes)
			(effects
				(font
					(size 1.27 1.27)
				)
			)
		)
		(property "Value" ""
			(at 0 0 270)
			(layer "F.Fab")
			(effects
				(font
					(size 1.27 1.27)
				)
			)
		)
		(duplicate_pad_numbers_are_jumpers no)
		(fp_line
			(start -0.7874 0.4064)
			(end -0.7874 -0.4064)
			(stroke
				(width 0.1524)
				(type default)
			)
			(layer "F.SilkS")
		)
		(fp_line
			(start 0.7874 0.4064)
			(end -0.7874 0.4064)
			(stroke
				(width 0.1524)
				(type default)
			)
			(layer "F.SilkS")
		)
		(fp_line
			(start -0.7874 -0.4064)
			(end 0.7874 -0.4064)
			(stroke
				(width 0.1524)
				(type default)
			)
			(layer "F.SilkS")
		)
		(fp_line
			(start 0.7874 -0.4064)
			(end 0.7874 0.4064)
			(stroke
				(width 0.1524)
				(type default)
			)
			(layer "F.SilkS")
		)
		(fp_line
			(start -0.67945 0.3048)
			(end -0.67945 -0.305054)
			(stroke
				(width 0.1)
				(type default)
			)
			(layer "F.Fab")
		)
		(fp_line
			(start -0.12065 0.3048)
			(end -0.67945 0.3048)
			(stroke
				(width 0.1)
				(type default)
			)
			(layer "F.Fab")
		)
		(fp_line
			(start 0.120396 0.3048)
			(end 0.120396 0.2794)
			(stroke
				(width 0.1)
				(type default)
			)
			(layer "F.Fab")
		)
		(fp_line
			(start 0.67945 0.3048)
			(end 0.120396 0.3048)
			(stroke
				(width 0.1)
				(type default)
			)
			(layer "F.Fab")
		)
		(fp_line
			(start -0.12065 0.2794)
			(end -0.12065 0.3048)
			(stroke
				(width 0.1)
				(type default)
			)
			(layer "F.Fab")
		)
		(fp_line
			(start 0.120396 0.2794)
			(end -0.12065 0.2794)
			(stroke
				(width 0.1)
				(type default)
			)
			(layer "F.Fab")
		)
		(fp_line
			(start -0.12065 -0.2794)
			(end 0.12065 -0.2794)
			(stroke
				(width 0.1)
				(type default)
			)
			(layer "F.Fab")
		)
		(fp_line
			(start 0.12065 -0.2794)
			(end 0.12065 -0.3048)
			(stroke
				(width 0.1)
				(type default)
			)
			(layer "F.Fab")
		)
		(fp_line
			(start 0.12065 -0.3048)
			(end 0.67945 -0.3048)
			(stroke
				(width 0.1)
				(type default)
			)
			(layer "F.Fab")
		)
		(fp_line
			(start 0.67945 -0.3048)
			(end 0.67945 0.3048)
			(stroke
				(width 0.1)
				(type default)
			)
			(layer "F.Fab")
		)
		(fp_line
			(start -0.67945 -0.305054)
			(end -0.12065 -0.305054)
			(stroke
				(width 0.1)
				(type default)
			)
			(layer "F.Fab")
		)
		(fp_line
			(start -0.12065 -0.305054)
			(end -0.12065 -0.2794)
			(stroke
				(width 0.1)
				(type default)
			)
			(layer "F.Fab")
		)
		(pad "1" smd circle
			(at -0.40005 0 270)
			(size 0 0)
			(layers "F.Cu" "F.Mask" "F.Paste")
			(net "P3V3_AUX")
		)
		(pad "2" smd circle
			(at 0.40005 0 270)
			(size 0 0)
			(layers "F.Cu" "F.Mask" "F.Paste")
			(net "GND")
		)
	)
)
